(kicad_pcb
	(version 20260206)
	(generator "pcbnew")
	(generator_version "10.0")
	(general
		(thickness 1.6)
		(legacy_teardrops no)
	)
	(paper "A4")
	(title_block
		(title "12092022_DA0F0TFB6D0_F0T_FAN_BOARD_MP5048_D_brd_v02_OCP.brd")
		(comment 1 "Grand Teton / footprints 477-481 of 924")
	)
	(layers
		(0 "F.Cu" signal "TOP")
		(4 "In1.Cu" signal "GND")
		(6 "In2.Cu" signal "IN1")
		(8 "In3.Cu" signal "IN2")
		(10 "In4.Cu" signal "GND1")
		(2 "B.Cu" signal "BOTTOM")
		(9 "F.Adhes" user "F.Adhesive")
		(11 "B.Adhes" user "B.Adhesive")
		(13 "F.Paste" user "Package Geometry/Pastemask Top")
		(15 "B.Paste" user "Package Geometry/Pastemask Bottom")
		(5 "F.SilkS" user "Ref Des/Silkscreen Top")
		(7 "B.SilkS" user "Ref Des/Silkscreen Bottom")
		(1 "F.Mask" user "Board Geometry/Soldermask Top")
		(3 "B.Mask" user "Board Geometry/Soldermask Bottom")
		(17 "Dwgs.User" user "User.Drawings")
		(19 "Cmts.User" user "User.Comments")
		(21 "Eco1.User" user "User.Eco1")
		(23 "Eco2.User" user "User.Eco2")
		(25 "Edge.Cuts" user "Board Geometry/Outline")
		(27 "Margin" user)
		(31 "F.CrtYd" user "Package Geometry/Place Bound Top")
		(29 "B.CrtYd" user "Package Geometry/Place Bound Bottom")
		(35 "F.Fab" user "Ref Des/Assembly Top")
		(33 "B.Fab" user "Ref Des/Assembly Bottom")
	)
	(footprint ""
		(layer "F.Cu")
		(at 15.377922 -290.2331 180)
		(property "Reference" "D260"
			(at 5.217922 -0.06477 0)
			(unlocked yes)
			(layer "F.SilkS")
			(effects
				(font
					(size 0.7874 0.5842)
					(thickness 0.1524)
				)
				(justify left)
			)
		)
		(property "Value" ""
			(at 0 0 180)
			(layer "F.Fab")
			(effects
				(font
					(size 1.27 1.27)
				)
			)
		)
		(duplicate_pad_numbers_are_jumpers no)
		(fp_line
			(start 0.94488 0.450088)
			(end 0.94488 -0.450088)
			(stroke
				(width 0.1524)
				(type default)
			)
			(layer "F.SilkS")
		)
		(fp_line
			(start 0.94488 -0.450088)
			(end -0.854964 -0.450088)
			(stroke
				(width 0.1524)
				(type default)
			)
			(layer "F.SilkS")
		)
		(fp_line
			(start 0.870458 -0.2794)
			(end 0.845058 0.4064)
			(stroke
				(width 0.1524)
				(type default)
			)
			(layer "F.SilkS")
		)
		(fp_line
			(start 0.845058 0.4064)
			(end 0.845058 -0.381)
			(stroke
				(width 0.1524)
				(type default)
			)
			(layer "F.SilkS")
		)
		(fp_line
			(start -0.854964 0.450088)
			(end 0.925068 0.450088)
			(stroke
				(width 0.1524)
				(type default)
			)
			(layer "F.SilkS")
		)
		(fp_line
			(start -0.854964 -0.450088)
			(end -0.854964 0.450088)
			(stroke
				(width 0.1524)
				(type default)
			)
			(layer "F.SilkS")
		)
		(fp_line
			(start 0.54991 0.350012)
			(end 0.54991 -0.350012)
			(stroke
				(width 0.1)
				(type default)
			)
			(layer "F.Fab")
		)
		(fp_line
			(start 0.54991 -0.350012)
			(end -0.54991 -0.350012)
			(stroke
				(width 0.1)
				(type default)
			)
			(layer "F.Fab")
		)
		(fp_line
			(start -0.54991 0.350012)
			(end 0.54991 0.350012)
			(stroke
				(width 0.1)
				(type default)
			)
			(layer "F.Fab")
		)
		(fp_line
			(start -0.54991 -0.350012)
			(end -0.54991 0.350012)
			(stroke
				(width 0.1)
				(type default)
			)
			(layer "F.Fab")
		)
		(fp_text user "-"
			(at 2.169922 -0.32385 0)
			(unlocked yes)
			(layer "F.SilkS")
			(effects
				(font
					(size 1.905 1.4224)
					(thickness 0.1524)
				)
				(justify left)
			)
		)
		(fp_text user "+"
			(at -0.808228 0.239014 0)
			(unlocked yes)
			(layer "F.SilkS")
			(effects
				(font
					(size 1.905 1.4224)
					(thickness 0.1524)
				)
				(justify left)
			)
		)
		(fp_text user "-"
			(at 2.48539 0.239014 0)
			(unlocked yes)
			(layer "F.Fab")
			(effects
				(font
					(size 1.905 1.4224)
					(thickness 0.1524)
				)
				(justify left)
			)
		)
		(fp_text user "+"
			(at -0.808228 0.239014 0)
			(unlocked yes)
			(layer "F.Fab")
			(effects
				(font
					(size 1.905 1.4224)
					(thickness 0.1524)
				)
				(justify left)
			)
		)
		(pad "A" smd rect
			(at -0.424942 0 180)
			(size 0.5588 0.6096)
			(layers "F.Cu" "F.Mask" "F.Paste")
			(net "GND")
		)
		(pad "C" smd rect
			(at 0.424942 0)
			(size 0.5588 0.6096)
			(layers "F.Cu" "F.Mask" "F.Paste")
			(net "FAN_7_TACH_IL_D")
		)
	)
	(footprint ""
		(layer "F.Cu")
		(at 15.377922 -302.4251 180)
		(property "Reference" "D144"
			(at 5.852922 -0.06477 0)
			(unlocked yes)
			(layer "F.SilkS")
			(effects
				(font
					(size 0.7874 0.5842)
					(thickness 0.1524)
				)
				(justify left)
			)
		)
		(property "Value" ""
			(at 0 0 180)
			(layer "F.Fab")
			(effects
				(font
					(size 1.27 1.27)
				)
			)
		)
		(duplicate_pad_numbers_are_jumpers no)
		(fp_line
			(start 1.778 0.6858)
			(end 1.778 -0.6858)
			(stroke
				(width 0.1524)
				(type default)
			)
			(layer "F.SilkS")
		)
		(fp_line
			(start 1.651 -0.6858)
			(end 1.651 0.6858)
			(stroke
				(width 0.1524)
				(type default)
			)
			(layer "F.SilkS")
		)
		(fp_line
			(start 0.299974 -0.500126)
			(end 0.299974 0.500126)
			(stroke
				(width 0.1524)
				(type default)
			)
			(layer "F.SilkS")
		)
		(fp_line
			(start 0.199898 0)
			(end -0.299974 -0.500126)
			(stroke
				(width 0.1524)
				(type default)
			)
			(layer "F.SilkS")
		)
		(fp_line
			(start -0.299974 0.500126)
			(end 0.199898 0)
			(stroke
				(width 0.1524)
				(type default)
			)
			(layer "F.SilkS")
		)
		(fp_line
			(start -0.299974 -0.500126)
			(end -0.299974 0.500126)
			(stroke
				(width 0.1524)
				(type default)
			)
			(layer "F.SilkS")
		)
		(fp_line
			(start 1.35001 0.175006)
			(end 0.899922 0.175006)
			(stroke
				(width 0.1)
				(type default)
			)
			(layer "F.Fab")
		)
		(fp_line
			(start 1.35001 -0.225044)
			(end 1.35001 0.175006)
			(stroke
				(width 0.1)
				(type default)
			)
			(layer "F.Fab")
		)
		(fp_line
			(start 0.899922 0.700024)
			(end -0.899922 0.700024)
			(stroke
				(width 0.1)
				(type default)
			)
			(layer "F.Fab")
		)
		(fp_line
			(start 0.899922 0.175006)
			(end 0.899922 0.700024)
			(stroke
				(width 0.1)
				(type default)
			)
			(layer "F.Fab")
		)
		(fp_line
			(start 0.899922 -0.225044)
			(end 1.35001 -0.225044)
			(stroke
				(width 0.1)
				(type default)
			)
			(layer "F.Fab")
		)
		(fp_line
			(start 0.899922 -0.700024)
			(end 0.899922 -0.225044)
			(stroke
				(width 0.1)
				(type default)
			)
			(layer "F.Fab")
		)
		(fp_line
			(start 0.299974 -0.500126)
			(end 0.299974 0.500126)
			(stroke
				(width 0.1)
				(type default)
			)
			(layer "F.Fab")
		)
		(fp_line
			(start 0.199898 0)
			(end -0.299974 -0.500126)
			(stroke
				(width 0.1)
				(type default)
			)
			(layer "F.Fab")
		)
		(fp_line
			(start -0.299974 0.500126)
			(end 0.199898 0)
			(stroke
				(width 0.1)
				(type default)
			)
			(layer "F.Fab")
		)
		(fp_line
			(start -0.299974 -0.500126)
			(end -0.299974 0.500126)
			(stroke
				(width 0.1)
				(type default)
			)
			(layer "F.Fab")
		)
		(fp_line
			(start -0.899922 0.700024)
			(end -0.899922 0.175006)
			(stroke
				(width 0.1)
				(type default)
			)
			(layer "F.Fab")
		)
		(fp_line
			(start -0.899922 0.175006)
			(end -1.35001 0.175006)
			(stroke
				(width 0.1)
				(type default)
			)
			(layer "F.Fab")
		)
		(fp_line
			(start -0.899922 -0.225044)
			(end -0.899922 -0.700024)
			(stroke
				(width 0.1)
				(type default)
			)
			(layer "F.Fab")
		)
		(fp_line
			(start -0.899922 -0.700024)
			(end 0.899922 -0.700024)
			(stroke
				(width 0.1)
				(type default)
			)
			(layer "F.Fab")
		)
		(fp_line
			(start -1.35001 0.175006)
			(end -1.35001 -0.225044)
			(stroke
				(width 0.1)
				(type default)
			)
			(layer "F.Fab")
		)
		(fp_line
			(start -1.35001 -0.225044)
			(end -0.899922 -0.225044)
			(stroke
				(width 0.1)
				(type default)
			)
			(layer "F.Fab")
		)
		(fp_text user "-"
			(at 1.928622 0.38227 180)
			(unlocked yes)
			(layer "F.SilkS")
			(effects
				(font
					(size 1.905 1.4224)
					(thickness 0.1524)
				)
				(justify left)
			)
		)
		(fp_text user "+"
			(at -2.554478 -1.09855 180)
			(unlocked yes)
			(layer "F.SilkS")
			(effects
				(font
					(size 1.905 1.4224)
					(thickness 0.1524)
				)
				(justify left)
			)
		)
		(fp_text user "-"
			(at 1.8288 -0.24765 180)
			(unlocked yes)
			(layer "F.Fab")
			(effects
				(font
					(size 1.905 1.4224)
					(thickness 0.1524)
				)
				(justify left)
			)
		)
		(fp_text user "+"
			(at -2.794 -0.19685 180)
			(unlocked yes)
			(layer "F.Fab")
			(effects
				(font
					(size 1.905 1.4224)
					(thickness 0.1524)
				)
				(justify left)
			)
		)
		(pad "1" smd rect
			(at -1.0922 0)
			(size 0.8128 0.8636)
			(layers "F.Cu" "F.Mask" "F.Paste")
			(net "FAN_7_TACH_OL_R")
		)
		(pad "2" smd rect
			(at 1.0922 0 180)
			(size 0.8128 0.8636)
			(layers "F.Cu" "F.Mask" "F.Paste")
			(net "FAN_7_TACH_OL_D")
		)
	)
	(footprint ""
		(layer "F.Cu")
		(at 46.355 -165.608)
		(property "Reference" "R5115"
			(at 0 0 0)
			(layer "F.SilkS")
			(hide yes)
			(effects
				(font
					(size 1.27 1.27)
				)
			)
		)
		(property "Value" ""
			(at 0 0 0)
			(layer "F.Fab")
			(effects
				(font
					(size 1.27 1.27)
				)
			)
		)
		(duplicate_pad_numbers_are_jumpers no)
		(fp_line
			(start -0.7874 -0.4064)
			(end 0.7874 -0.4064)
			(stroke
				(width 0.1524)
				(type default)
			)
			(layer "F.SilkS")
		)
		(fp_line
			(start -0.7874 0.4064)
			(end -0.7874 -0.4064)
			(stroke
				(width 0.1524)
				(type default)
			)
			(layer "F.SilkS")
		)
		(fp_line
			(start 0.7874 -0.4064)
			(end 0.7874 0.4064)
			(stroke
				(width 0.1524)
				(type default)
			)
			(layer "F.SilkS")
		)
		(fp_line
			(start 0.7874 0.4064)
			(end -0.7874 0.4064)
			(stroke
				(width 0.1524)
				(type default)
			)
			(layer "F.SilkS")
		)
		(fp_line
			(start -0.67945 -0.305054)
			(end -0.12065 -0.305054)
			(stroke
				(width 0.1)
				(type default)
			)
			(layer "F.Fab")
		)
		(fp_line
			(start -0.67945 0.3048)
			(end -0.67945 -0.305054)
			(stroke
				(width 0.1)
				(type default)
			)
			(layer "F.Fab")
		)
		(fp_line
			(start -0.12065 -0.305054)
			(end -0.12065 -0.2794)
			(stroke
				(width 0.1)
				(type default)
			)
			(layer "F.Fab")
		)
		(fp_line
			(start -0.12065 -0.2794)
			(end 0.12065 -0.2794)
			(stroke
				(width 0.1)
				(type default)
			)
			(layer "F.Fab")
		)
		(fp_line
			(start -0.12065 0.2794)
			(end -0.12065 0.3048)
			(stroke
				(width 0.1)
				(type default)
			)
			(layer "F.Fab")
		)
		(fp_line
			(start -0.12065 0.3048)
			(end -0.67945 0.3048)
			(stroke
				(width 0.1)
				(type default)
			)
			(layer "F.Fab")
		)
		(fp_line
			(start 0.120396 0.2794)
			(end -0.12065 0.2794)
			(stroke
				(width 0.1)
				(type default)
			)
			(layer "F.Fab")
		)
		(fp_line
			(start 0.120396 0.3048)
			(end 0.120396 0.2794)
			(stroke
				(width 0.1)
				(type default)
			)
			(layer "F.Fab")
		)
		(fp_line
			(start 0.12065 -0.3048)
			(end 0.67945 -0.3048)
			(stroke
				(width 0.1)
				(type default)
			)
			(layer "F.Fab")
		)
		(fp_line
			(start 0.12065 -0.2794)
			(end 0.12065 -0.3048)
			(stroke
				(width 0.1)
				(type default)
			)
			(layer "F.Fab")
		)
		(fp_line
			(start 0.67945 -0.3048)
			(end 0.67945 0.3048)
			(stroke
				(width 0.1)
				(type default)
			)
			(layer "F.Fab")
		)
		(fp_line
			(start 0.67945 0.3048)
			(end 0.120396 0.3048)
			(stroke
				(width 0.1)
				(type default)
			)
			(layer "F.Fab")
		)
		(pad "1" smd circle
			(at -0.40005 0)
			(size 0 0)
			(layers "F.Cu" "F.Mask" "F.Paste")
			(net "PCA9552_MB1_A0")
		)
		(pad "2" smd circle
			(at 0.40005 0)
			(size 0 0)
			(layers "F.Cu" "F.Mask" "F.Paste")
			(net "GND")
		)
	)
	(footprint ""
		(layer "F.Cu")
		(at 4.191 -162.814 180)
		(property "Reference" "R100"
			(at 0 0 180)
			(layer "F.SilkS")
			(hide yes)
			(effects
				(font
					(size 1.27 1.27)
				)
			)
		)
		(property "Value" ""
			(at 0 0 180)
			(layer "F.Fab")
			(effects
				(font
					(size 1.27 1.27)
				)
			)
		)
		(duplicate_pad_numbers_are_jumpers no)
		(fp_line
			(start 0.7874 0.4064)
			(end -0.7874 0.4064)
			(stroke
				(width 0.1524)
				(type default)
			)
			(layer "F.SilkS")
		)
		(fp_line
			(start 0.7874 -0.4064)
			(end 0.7874 0.4064)
			(stroke
				(width 0.1524)
				(type default)
			)
			(layer "F.SilkS")
		)
		(fp_line
			(start -0.7874 0.4064)
			(end -0.7874 -0.4064)
			(stroke
				(width 0.1524)
				(type default)
			)
			(layer "F.SilkS")
		)
		(fp_line
			(start -0.7874 -0.4064)
			(end 0.7874 -0.4064)
			(stroke
				(width 0.1524)
				(type default)
			)
			(layer "F.SilkS")
		)
		(fp_line
			(start 0.67945 0.3048)
			(end 0.120396 0.3048)
			(stroke
				(width 0.1)
				(type default)
			)
			(layer "F.Fab")
		)
		(fp_line
			(start 0.67945 -0.3048)
			(end 0.67945 0.3048)
			(stroke
				(width 0.1)
				(type default)
			)
			(layer "F.Fab")
		)
		(fp_line
			(start 0.12065 -0.2794)
			(end 0.12065 -0.3048)
			(stroke
				(width 0.1)
				(type default)
			)
			(layer "F.Fab")
		)
		(fp_line
			(start 0.12065 -0.3048)
			(end 0.67945 -0.3048)
			(stroke
				(width 0.1)
				(type default)
			)
			(layer "F.Fab")
		)
		(fp_line
			(start 0.120396 0.3048)
			(end 0.120396 0.2794)
			(stroke
				(width 0.1)
				(type default)
			)
			(layer "F.Fab")
		)
		(fp_line
			(start 0.120396 0.2794)
			(end -0.12065 0.2794)
			(stroke
				(width 0.1)
				(type default)
			)
			(layer "F.Fab")
		)
		(fp_line
			(start -0.12065 0.3048)
			(end -0.67945 0.3048)
			(stroke
				(width 0.1)
				(type default)
			)
			(layer "F.Fab")
		)
		(fp_line
			(start -0.12065 0.2794)
			(end -0.12065 0.3048)
			(stroke
				(width 0.1)
				(type default)
			)
			(layer "F.Fab")
		)
		(fp_line
			(start -0.12065 -0.2794)
			(end 0.12065 -0.2794)
			(stroke
				(width 0.1)
				(type default)
			)
			(layer "F.Fab")
		)
		(fp_line
			(start -0.12065 -0.305054)
			(end -0.12065 -0.2794)
			(stroke
				(width 0.1)
				(type default)
			)
			(layer "F.Fab")
		)
		(fp_line
			(start -0.67945 0.3048)
			(end -0.67945 -0.305054)
			(stroke
				(width 0.1)
				(type default)
			)
			(layer "F.Fab")
		)
		(fp_line
			(start -0.67945 -0.305054)
			(end -0.12065 -0.305054)
			(stroke
				(width 0.1)
				(type default)
			)
			(layer "F.Fab")
		)
		(pad "1" smd circle
			(at -0.40005 0 180)
			(size 0 0)
			(layers "F.Cu" "F.Mask" "F.Paste")
			(net "FAN_0_PRSNT_BUF_R_N")
		)
		(pad "2" smd circle
			(at 0.40005 0 180)
			(size 0 0)
			(layers "F.Cu" "F.Mask" "F.Paste")
			(net "FAN_0_PRSNT_BUF_N")
		)
	)
	(footprint ""
		(layer "F.Cu")
		(at 27.432 -180.594 180)
		(property "Reference" "R5488"
			(at 0 0 180)
			(layer "F.SilkS")
			(hide yes)
			(effects
				(font
					(size 1.27 1.27)
				)
			)
		)
		(property "Value" ""
			(at 0 0 180)
			(layer "F.Fab")
			(effects
				(font
					(size 1.27 1.27)
				)
			)
		)
		(duplicate_pad_numbers_are_jumpers no)
		(fp_line
			(start 0.7874 0.4064)
			(end -0.7874 0.4064)
			(stroke
				(width 0.1524)
				(type default)
			)
			(layer "F.SilkS")
		)
		(fp_line
			(start 0.7874 -0.4064)
			(end 0.7874 0.4064)
			(stroke
				(width 0.1524)
				(type default)
			)
			(layer "F.SilkS")
		)
		(fp_line
			(start -0.7874 0.4064)
			(end -0.7874 -0.4064)
			(stroke
				(width 0.1524)
				(type default)
			)
			(layer "F.SilkS")
		)
		(fp_line
			(start -0.7874 -0.4064)
			(end 0.7874 -0.4064)
			(stroke
				(width 0.1524)
				(type default)
			)
			(layer "F.SilkS")
		)
		(fp_line
			(start 0.67945 0.3048)
			(end 0.120396 0.3048)
			(stroke
				(width 0.1)
				(type default)
			)
			(layer "F.Fab")
		)
		(fp_line
			(start 0.67945 -0.3048)
			(end 0.67945 0.3048)
			(stroke
				(width 0.1)
				(type default)
			)
			(layer "F.Fab")
		)
		(fp_line
			(start 0.12065 -0.2794)
			(end 0.12065 -0.3048)
			(stroke
				(width 0.1)
				(type default)
			)
			(layer "F.Fab")
		)
		(fp_line
			(start 0.12065 -0.3048)
			(end 0.67945 -0.3048)
			(stroke
				(width 0.1)
				(type default)
			)
			(layer "F.Fab")
		)
		(fp_line
			(start 0.120396 0.3048)
			(end 0.120396 0.2794)
			(stroke
				(width 0.1)
				(type default)
			)
			(layer "F.Fab")
		)
		(fp_line
			(start 0.120396 0.2794)
			(end -0.12065 0.2794)
			(stroke
				(width 0.1)
				(type default)
			)
			(layer "F.Fab")
		)
		(fp_line
			(start -0.12065 0.3048)
			(end -0.67945 0.3048)
			(stroke
				(width 0.1)
				(type default)
			)
			(layer "F.Fab")
		)
		(fp_line
			(start -0.12065 0.2794)
			(end -0.12065 0.3048)
			(stroke
				(width 0.1)
				(type default)
			)
			(layer "F.Fab")
		)
		(fp_line
			(start -0.12065 -0.2794)
			(end 0.12065 -0.2794)
			(stroke
				(width 0.1)
				(type default)
			)
			(layer "F.Fab")
		)
		(fp_line
			(start -0.12065 -0.305054)
			(end -0.12065 -0.2794)
			(stroke
				(width 0.1)
				(type default)
			)
			(layer "F.Fab")
		)
		(fp_line
			(start -0.67945 0.3048)
			(end -0.67945 -0.305054)
			(stroke
				(width 0.1)
				(type default)
			)
			(layer "F.Fab")
		)
		(fp_line
			(start -0.67945 -0.305054)
			(end -0.12065 -0.305054)
			(stroke
				(width 0.1)
				(type default)
			)
			(layer "F.Fab")
		)
		(pad "1" smd circle
			(at -0.40005 0 180)
			(size 0 0)
			(layers "F.Cu" "F.Mask" "F.Paste")
			(net "P52V_FAN_1_BUFF_EN")
		)
		(pad "2" smd circle
			(at 0.40005 0 180)
			(size 0 0)
			(layers "F.Cu" "F.Mask" "F.Paste")
			(net "P52V_FAN_1_BUFF_EN_R")
		)
	)
)
